(kicad_pcb
	(version 20260206)
	(generator "pcbnew")
	(generator_version "10.0")
	(general
		(thickness 1.6)
		(legacy_teardrops no)
	)
	(paper "A4")
	(title_block
		(title "Bryce Canyon_F.DPB_16315-1-OCP.brd")
		(comment 1 "Bryce Canyon / footprints 261-267 of 2223")
	)
	(layers
		(0 "F.Cu" signal "TOP")
		(4 "In1.Cu" signal "L2GND")
		(6 "In2.Cu" signal "L3")
		(8 "In3.Cu" signal "L4GND")
		(10 "In4.Cu" signal "L5")
		(12 "In5.Cu" signal "L6VCC")
		(14 "In6.Cu" signal "L7VCC")
		(16 "In7.Cu" signal "L8")
		(18 "In8.Cu" signal "L9GND")
		(20 "In9.Cu" signal "L10")
		(22 "In10.Cu" signal "L11GND")
		(2 "B.Cu" signal "BOTTOM")
		(9 "F.Adhes" user "F.Adhesive")
		(11 "B.Adhes" user "B.Adhesive")
		(13 "F.Paste" user "Package Geometry/Pastemask Top")
		(15 "B.Paste" user "Package Geometry/Pastemask Bottom")
		(5 "F.SilkS" user "Ref Des/Silkscreen Top")
		(7 "B.SilkS" user "Ref Des/Silkscreen Bottom")
		(1 "F.Mask" user "Board Geometry/Soldermask Top")
		(3 "B.Mask" user "Board Geometry/Soldermask Bottom")
		(17 "Dwgs.User" user "User.Drawings")
		(19 "Cmts.User" user "User.Comments")
		(21 "Eco1.User" user "User.Eco1")
		(23 "Eco2.User" user "User.Eco2")
		(25 "Edge.Cuts" user "Board Geometry/Outline")
		(27 "Margin" user)
		(31 "F.CrtYd" user "Package Geometry/Place Bound Top")
		(29 "B.CrtYd" user "Package Geometry/Place Bound Bottom")
		(35 "F.Fab" user "Ref Des/Assembly Top")
		(33 "B.Fab" user "Ref Des/Assembly Bottom")
	)
	(footprint ""
		(layer "F.Cu")
		(at 276.6822 18.727928)
		(property "Reference" "Q3"
			(at 0 0 0)
			(layer "F.SilkS")
			(hide yes)
			(effects
				(font
					(size 1.27 1.27)
				)
			)
		)
		(property "Value" "2N7002KDW-GP"
			(at -2.3622 -8.2042 0)
			(unlocked yes)
			(layer "F.Fab")
			(hide yes)
			(effects
				(font
					(size 1.016 1.016)
					(thickness 0.1524)
				)
			)
		)
		(property "Device Type" "SOT-363H44"
			(at -2.3622 -10.1092 0)
			(unlocked yes)
			(layer "F.Fab")
			(hide yes)
			(effects
				(font
					(size 1.016 1.016)
					(thickness 0.1524)
				)
			)
		)
		(duplicate_pad_numbers_are_jumpers no)
		(fp_line
			(start -1.4478 -1.7018)
			(end -1.4478 1.7018)
			(stroke
				(width 0.1524)
				(type default)
			)
			(layer "F.SilkS")
		)
		(fp_line
			(start -1.4478 1.7018)
			(end 1.4478 1.7018)
			(stroke
				(width 0.1524)
				(type default)
			)
			(layer "F.SilkS")
		)
		(fp_line
			(start -1.27 1.524)
			(end -1.27 0.6604)
			(stroke
				(width 0.4826)
				(type default)
			)
			(layer "F.SilkS")
		)
		(fp_line
			(start 1.4478 -1.7018)
			(end -1.4478 -1.7018)
			(stroke
				(width 0.1524)
				(type default)
			)
			(layer "F.SilkS")
		)
		(fp_line
			(start 1.4478 1.7018)
			(end 1.4478 -1.7018)
			(stroke
				(width 0.1524)
				(type default)
			)
			(layer "F.SilkS")
		)
		(fp_poly
			(pts
				(xy -1.524 -1.778) (xy 1.524 -1.778) (xy 1.524 1.778) (xy -1.524 1.778)
			)
			(stroke
				(width 0)
				(type default)
			)
			(fill no)
			(layer "F.CrtYd")
		)
		(fp_poly
			(pts
				(xy -1.524 -1.778) (xy 1.524 -1.778) (xy 1.524 1.778) (xy -1.524 1.778)
			)
			(stroke
				(width 0)
				(type default)
			)
			(fill no)
			(layer "F.Fab")
		)
		(pad "1" smd rect
			(at -0.65024 0.9398)
			(size 0.4064 1.016)
			(layers "F.Cu" "F.Mask" "F.Paste")
			(net "GND")
		)
		(pad "2" smd rect
			(at 0 0.9398)
			(size 0.4064 1.016)
			(layers "F.Cu" "F.Mask" "F.Paste")
			(net "SCC_B_PWR_LED")
		)
		(pad "3" smd rect
			(at 0.65024 0.9398)
			(size 0.4064 1.016)
			(layers "F.Cu" "F.Mask" "F.Paste")
			(net "SYS_PWR_LED_B")
		)
		(pad "4" smd rect
			(at 0.65024 -0.9398)
			(size 0.4064 1.016)
			(layers "F.Cu" "F.Mask" "F.Paste")
			(net "GND")
		)
		(pad "5" smd rect
			(at 0 -0.9398)
			(size 0.4064 1.016)
			(layers "F.Cu" "F.Mask" "F.Paste")
			(net "IOM_B_PWR_LED")
		)
		(pad "6" smd rect
			(at -0.65024 -0.9398)
			(size 0.4064 1.016)
			(layers "F.Cu" "F.Mask" "F.Paste")
			(net "SYS_PWR_LED_B")
		)
	)
	(footprint ""
		(layer "F.Cu")
		(at 332.105 -275.252942 -90)
		(property "Reference" "Q37"
			(at 0 0 270)
			(layer "F.SilkS")
			(hide yes)
			(effects
				(font
					(size 1.27 1.27)
				)
			)
		)
		(property "Value" "2N7002KDW-GP"
			(at -2.3622 -8.2042 270)
			(unlocked yes)
			(layer "F.Fab")
			(hide yes)
			(effects
				(font
					(size 1.016 1.016)
					(thickness 0.1524)
				)
			)
		)
		(property "Device Type" "SOT-363H44"
			(at -2.3622 -10.1092 270)
			(unlocked yes)
			(layer "F.Fab")
			(hide yes)
			(effects
				(font
					(size 1.016 1.016)
					(thickness 0.1524)
				)
			)
		)
		(duplicate_pad_numbers_are_jumpers no)
		(fp_line
			(start -1.4478 1.7018)
			(end 1.4478 1.7018)
			(stroke
				(width 0.1524)
				(type default)
			)
			(layer "F.SilkS")
		)
		(fp_line
			(start 1.4478 1.7018)
			(end 1.4478 -1.7018)
			(stroke
				(width 0.1524)
				(type default)
			)
			(layer "F.SilkS")
		)
		(fp_line
			(start -1.27 1.524)
			(end -1.27 0.6604)
			(stroke
				(width 0.4826)
				(type default)
			)
			(layer "F.SilkS")
		)
		(fp_line
			(start -1.4478 -1.7018)
			(end -1.4478 1.7018)
			(stroke
				(width 0.1524)
				(type default)
			)
			(layer "F.SilkS")
		)
		(fp_line
			(start 1.4478 -1.7018)
			(end -1.4478 -1.7018)
			(stroke
				(width 0.1524)
				(type default)
			)
			(layer "F.SilkS")
		)
		(fp_poly
			(pts
				(xy -1.524 -1.778) (xy 1.524 -1.778) (xy 1.524 1.778) (xy -1.524 1.778)
			)
			(stroke
				(width 0)
				(type default)
			)
			(fill no)
			(layer "F.CrtYd")
		)
		(fp_poly
			(pts
				(xy -1.524 -1.778) (xy 1.524 -1.778) (xy 1.524 1.778) (xy -1.524 1.778)
			)
			(stroke
				(width 0)
				(type default)
			)
			(fill no)
			(layer "F.Fab")
		)
		(pad "1" smd rect
			(at -0.65024 0.9398 270)
			(size 0.4064 1.016)
			(layers "F.Cu" "F.Mask" "F.Paste")
			(net "GND")
		)
		(pad "2" smd rect
			(at 0 0.9398 270)
			(size 0.4064 1.016)
			(layers "F.Cu" "F.Mask" "F.Paste")
			(net "SW_PWR_R_HDD6")
		)
		(pad "3" smd rect
			(at 0.65024 0.9398 270)
			(size 0.4064 1.016)
			(layers "F.Cu" "F.Mask" "F.Paste")
			(net "SW_HDD_P6")
		)
		(pad "4" smd rect
			(at 0.65024 -0.9398 270)
			(size 0.4064 1.016)
			(layers "F.Cu" "F.Mask" "F.Paste")
			(net "GND")
		)
		(pad "5" smd rect
			(at 0 -0.9398 270)
			(size 0.4064 1.016)
			(layers "F.Cu" "F.Mask" "F.Paste")
			(net "SW_HDD_G6")
		)
		(pad "6" smd rect
			(at -0.65024 -0.9398 270)
			(size 0.4064 1.016)
			(layers "F.Cu" "F.Mask" "F.Paste")
			(net "SW_HDD_R6")
		)
	)
	(footprint ""
		(layer "F.Cu")
		(at 329.819 -74.335894 180)
		(property "Reference" "C437"
			(at 0 0 180)
			(layer "F.SilkS")
			(hide yes)
			(effects
				(font
					(size 1.27 1.27)
				)
			)
		)
		(property "Value" "SC1U25V3KX-GP"
			(at 0 -2.8194 180)
			(unlocked yes)
			(layer "F.Fab")
			(hide yes)
			(effects
				(font
					(size 1.016 1.016)
					(thickness 0.1524)
				)
			)
		)
		(property "Device Type" "C603H36"
			(at 0 -4.3434 180)
			(unlocked yes)
			(layer "F.Fab")
			(hide yes)
			(effects
				(font
					(size 1.016 1.016)
					(thickness 0.1524)
				)
			)
		)
		(duplicate_pad_numbers_are_jumpers no)
		(fp_line
			(start 0.508 0)
			(end -0.508 0)
			(stroke
				(width 0.2032)
				(type default)
			)
			(layer "F.SilkS")
		)
		(fp_rect
			(start -0.5842 1.3335)
			(end 0.5842 -1.3335)
			(stroke
				(width 0)
				(type default)
			)
			(fill no)
			(layer "F.CrtYd")
		)
		(fp_rect
			(start -0.5842 1.3335)
			(end 0.5842 -1.3335)
			(stroke
				(width 0)
				(type default)
			)
			(fill no)
			(layer "F.Fab")
		)
		(pad "1" smd custom
			(at 0 -0.762 180)
			(size 0.2159 0.2159)
			(layers "F.Cu" "F.Mask" "F.Paste")
			(net "P12V_HDD30")
			(options
				(clearance outline)
				(anchor circle)
			)
			(primitives
				(gr_poly
					(pts
						(arc
							(start -0.3302 -0.4318)
							(mid -0.402042 -0.402042)
							(end -0.4318 -0.3302)
						)
						(arc
							(start -0.4318 0.3302)
							(mid -0.402042 0.402042)
							(end -0.3302 0.4318)
						)
						(arc
							(start 0.3302 0.4318)
							(mid 0.402042 0.402042)
							(end 0.4318 0.3302)
						)
						(arc
							(start 0.4318 -0.3302)
							(mid 0.402042 -0.402042)
							(end 0.3302 -0.4318)
						)
					)
					(width 0)
					(fill yes)
				)
			)
		)
		(pad "2" smd custom
			(at 0 0.762 180)
			(size 0.2159 0.2159)
			(layers "F.Cu" "F.Mask" "F.Paste")
			(net "GND")
			(options
				(clearance outline)
				(anchor circle)
			)
			(primitives
				(gr_poly
					(pts
						(arc
							(start -0.3302 -0.4318)
							(mid -0.402042 -0.402042)
							(end -0.4318 -0.3302)
						)
						(arc
							(start -0.4318 0.3302)
							(mid -0.402042 0.402042)
							(end -0.3302 0.4318)
						)
						(arc
							(start 0.3302 0.4318)
							(mid 0.402042 0.402042)
							(end 0.4318 0.3302)
						)
						(arc
							(start 0.4318 -0.3302)
							(mid 0.402042 -0.402042)
							(end 0.3302 -0.4318)
						)
					)
					(width 0)
					(fill yes)
				)
			)
		)
	)
	(footprint ""
		(layer "F.Cu")
		(at 466.3948 -288.26968 180)
		(property "Reference" "R599"
			(at 0 0 180)
			(layer "F.SilkS")
			(hide yes)
			(effects
				(font
					(size 1.27 1.27)
				)
			)
		)
		(property "Value" "4K7R2J-2-GP"
			(at 0.064008 -3.993896 180)
			(unlocked yes)
			(layer "F.Fab")
			(hide yes)
			(effects
				(font
					(size 1.016 1.016)
					(thickness 0.1524)
				)
			)
		)
		(property "Device Type" "R402H16"
			(at 0.064008 -5.517896 180)
			(unlocked yes)
			(layer "F.Fab")
			(hide yes)
			(effects
				(font
					(size 1.016 1.016)
					(thickness 0.1524)
				)
			)
		)
		(duplicate_pad_numbers_are_jumpers no)
		(fp_line
			(start 0.508 -0.9398)
			(end -0.508 -0.9398)
			(stroke
				(width 0.1524)
				(type default)
			)
			(layer "F.SilkS")
		)
		(fp_line
			(start -0.508 -0.9398)
			(end -0.508 0.9398)
			(stroke
				(width 0.1524)
				(type default)
			)
			(layer "F.SilkS")
		)
		(fp_rect
			(start -0.508 0.9398)
			(end 0.508 -0.9398)
			(stroke
				(width 0)
				(type default)
			)
			(fill no)
			(layer "F.CrtYd")
		)
		(fp_rect
			(start -0.508 0.9398)
			(end 0.508 -0.9398)
			(stroke
				(width 0)
				(type default)
			)
			(fill no)
			(layer "F.Fab")
		)
		(pad "1" smd custom
			(at 0 -0.4445 180)
			(size 0.1397 0.1397)
			(layers "F.Cu" "F.Mask" "F.Paste")
			(net "DRIVE_B_35_ACT")
			(options
				(clearance outline)
				(anchor circle)
			)
			(primitives
				(gr_poly
					(pts
						(arc
							(start -0.1778 -0.2794)
							(mid -0.249642 -0.249642)
							(end -0.2794 -0.1778)
						)
						(arc
							(start -0.2794 0.1778)
							(mid -0.249642 0.249642)
							(end -0.1778 0.2794)
						)
						(arc
							(start 0.1778 0.2794)
							(mid 0.249642 0.249642)
							(end 0.2794 0.1778)
						)
						(arc
							(start 0.2794 -0.1778)
							(mid 0.249642 -0.249642)
							(end 0.1778 -0.2794)
						)
					)
					(width 0)
					(fill yes)
				)
			)
		)
		(pad "2" smd custom
			(at 0 0.4445 180)
			(size 0.1397 0.1397)
			(layers "F.Cu" "F.Mask" "F.Paste")
			(net "GND")
			(options
				(clearance outline)
				(anchor circle)
			)
			(primitives
				(gr_poly
					(pts
						(arc
							(start -0.1778 -0.2794)
							(mid -0.249642 -0.249642)
							(end -0.2794 -0.1778)
						)
						(arc
							(start -0.2794 0.1778)
							(mid -0.249642 0.249642)
							(end -0.1778 0.2794)
						)
						(arc
							(start 0.1778 0.2794)
							(mid 0.249642 0.249642)
							(end 0.2794 0.1778)
						)
						(arc
							(start 0.2794 -0.1778)
							(mid 0.249642 -0.249642)
							(end 0.1778 -0.2794)
						)
					)
					(width 0)
					(fill yes)
				)
			)
		)
	)
	(footprint ""
		(layer "F.Cu")
		(at 223.843342 -207.290162 90)
		(property "Reference" "R416"
			(at 0 0 90)
			(layer "F.SilkS")
			(hide yes)
			(effects
				(font
					(size 1.27 1.27)
				)
			)
		)
		(property "Value" "0R2J-2-GP"
			(at 0.064008 -3.993896 90)
			(unlocked yes)
			(layer "F.Fab")
			(hide yes)
			(effects
				(font
					(size 1.016 1.016)
					(thickness 0.1524)
				)
			)
		)
		(property "Device Type" "R402H16"
			(at 0.064008 -5.517896 90)
			(unlocked yes)
			(layer "F.Fab")
			(hide yes)
			(effects
				(font
					(size 1.016 1.016)
					(thickness 0.1524)
				)
			)
		)
		(duplicate_pad_numbers_are_jumpers no)
		(fp_line
			(start 0.508 -0.9398)
			(end -0.508 -0.9398)
			(stroke
				(width 0.1524)
				(type default)
			)
			(layer "F.SilkS")
		)
		(fp_line
			(start -0.508 -0.9398)
			(end -0.508 0.9398)
			(stroke
				(width 0.1524)
				(type default)
			)
			(layer "F.SilkS")
		)
		(fp_rect
			(start -0.508 0.9398)
			(end 0.508 -0.9398)
			(stroke
				(width 0)
				(type default)
			)
			(fill no)
			(layer "F.CrtYd")
		)
		(fp_rect
			(start -0.508 0.9398)
			(end 0.508 -0.9398)
			(stroke
				(width 0)
				(type default)
			)
			(fill no)
			(layer "F.Fab")
		)
		(pad "1" smd custom
			(at 0 -0.4445 90)
			(size 0.1397 0.1397)
			(layers "F.Cu" "F.Mask" "F.Paste")
			(net "I2C_SCC_A_SCL_BUF")
			(options
				(clearance outline)
				(anchor circle)
			)
			(primitives
				(gr_poly
					(pts
						(arc
							(start -0.1778 -0.2794)
							(mid -0.249642 -0.249642)
							(end -0.2794 -0.1778)
						)
						(arc
							(start -0.2794 0.1778)
							(mid -0.249642 0.249642)
							(end -0.1778 0.2794)
						)
						(arc
							(start 0.1778 0.2794)
							(mid 0.249642 0.249642)
							(end 0.2794 0.1778)
						)
						(arc
							(start 0.2794 -0.1778)
							(mid 0.249642 -0.249642)
							(end 0.1778 -0.2794)
						)
					)
					(width 0)
					(fill yes)
				)
			)
		)
		(pad "2" smd custom
			(at 0 0.4445 90)
			(size 0.1397 0.1397)
			(layers "F.Cu" "F.Mask" "F.Paste")
			(net "I2C_SCC_A_SCL")
			(options
				(clearance outline)
				(anchor circle)
			)
			(primitives
				(gr_poly
					(pts
						(arc
							(start -0.1778 -0.2794)
							(mid -0.249642 -0.249642)
							(end -0.2794 -0.1778)
						)
						(arc
							(start -0.2794 0.1778)
							(mid -0.249642 0.249642)
							(end -0.1778 0.2794)
						)
						(arc
							(start 0.1778 0.2794)
							(mid 0.249642 0.249642)
							(end 0.2794 0.1778)
						)
						(arc
							(start 0.2794 -0.1778)
							(mid 0.249642 -0.249642)
							(end 0.1778 -0.2794)
						)
					)
					(width 0)
					(fill yes)
				)
			)
		)
	)
	(footprint ""
		(layer "F.Cu")
		(at 332.74 -163.554918 -90)
		(property "Reference" "R551"
			(at 0 0 270)
			(layer "F.SilkS")
			(hide yes)
			(effects
				(font
					(size 1.27 1.27)
				)
			)
		)
		(property "Value" "4K7R2J-2-GP"
			(at 0.064008 -3.993896 270)
			(unlocked yes)
			(layer "F.Fab")
			(hide yes)
			(effects
				(font
					(size 1.016 1.016)
					(thickness 0.1524)
				)
			)
		)
		(property "Device Type" "R402H16"
			(at 0.064008 -5.517896 270)
			(unlocked yes)
			(layer "F.Fab")
			(hide yes)
			(effects
				(font
					(size 1.016 1.016)
					(thickness 0.1524)
				)
			)
		)
		(duplicate_pad_numbers_are_jumpers no)
		(fp_line
			(start -0.508 -0.9398)
			(end -0.508 0.9398)
			(stroke
				(width 0.1524)
				(type default)
			)
			(layer "F.SilkS")
		)
		(fp_line
			(start 0.508 -0.9398)
			(end -0.508 -0.9398)
			(stroke
				(width 0.1524)
				(type default)
			)
			(layer "F.SilkS")
		)
		(fp_rect
			(start -0.508 0.9398)
			(end 0.508 -0.9398)
			(stroke
				(width 0)
				(type default)
			)
			(fill no)
			(layer "F.CrtYd")
		)
		(fp_rect
			(start -0.508 0.9398)
			(end 0.508 -0.9398)
			(stroke
				(width 0)
				(type default)
			)
			(fill no)
			(layer "F.Fab")
		)
		(pad "1" smd custom
			(at 0 -0.4445 270)
			(size 0.1397 0.1397)
			(layers "F.Cu" "F.Mask" "F.Paste")
			(net "P12V_A")
			(options
				(clearance outline)
				(anchor circle)
			)
			(primitives
				(gr_poly
					(pts
						(arc
							(start -0.1778 -0.2794)
							(mid -0.249642 -0.249642)
							(end -0.2794 -0.1778)
						)
						(arc
							(start -0.2794 0.1778)
							(mid -0.249642 0.249642)
							(end -0.1778 0.2794)
						)
						(arc
							(start 0.1778 0.2794)
							(mid 0.249642 0.249642)
							(end 0.2794 0.1778)
						)
						(arc
							(start 0.2794 -0.1778)
							(mid 0.249642 -0.249642)
							(end 0.1778 -0.2794)
						)
					)
					(width 0)
					(fill yes)
				)
			)
		)
		(pad "2" smd custom
			(at 0 0.4445 270)
			(size 0.1397 0.1397)
			(layers "F.Cu" "F.Mask" "F.Paste")
			(net "SW_HDD_P18")
			(options
				(clearance outline)
				(anchor circle)
			)
			(primitives
				(gr_poly
					(pts
						(arc
							(start -0.1778 -0.2794)
							(mid -0.249642 -0.249642)
							(end -0.2794 -0.1778)
						)
						(arc
							(start -0.2794 0.1778)
							(mid -0.249642 0.249642)
							(end -0.1778 0.2794)
						)
						(arc
							(start 0.1778 0.2794)
							(mid 0.249642 0.249642)
							(end 0.2794 0.1778)
						)
						(arc
							(start 0.2794 -0.1778)
							(mid 0.249642 -0.249642)
							(end 0.1778 -0.2794)
						)
					)
					(width 0)
					(fill yes)
				)
			)
		)
	)
	(footprint ""
		(layer "F.Cu")
		(at 11.647678 -130.306064 -90)
		(property "Reference" "R501"
			(at 0 0 270)
			(layer "F.SilkS")
			(hide yes)
			(effects
				(font
					(size 1.27 1.27)
				)
			)
		)
		(property "Value" "4K7R2J-2-GP"
			(at 0.064008 -3.993896 270)
			(unlocked yes)
			(layer "F.Fab")
			(hide yes)
			(effects
				(font
					(size 1.016 1.016)
					(thickness 0.1524)
				)
			)
		)
		(property "Device Type" "R402H16"
			(at 0.064008 -5.517896 270)
			(unlocked yes)
			(layer "F.Fab")
			(hide yes)
			(effects
				(font
					(size 1.016 1.016)
					(thickness 0.1524)
				)
			)
		)
		(duplicate_pad_numbers_are_jumpers no)
		(fp_line
			(start -0.508 -0.9398)
			(end -0.508 0.9398)
			(stroke
				(width 0.1524)
				(type default)
			)
			(layer "F.SilkS")
		)
		(fp_line
			(start 0.508 -0.9398)
			(end -0.508 -0.9398)
			(stroke
				(width 0.1524)
				(type default)
			)
			(layer "F.SilkS")
		)
		(fp_rect
			(start -0.508 0.9398)
			(end 0.508 -0.9398)
			(stroke
				(width 0)
				(type default)
			)
			(fill no)
			(layer "F.CrtYd")
		)
		(fp_rect
			(start -0.508 0.9398)
			(end 0.508 -0.9398)
			(stroke
				(width 0)
				(type default)
			)
			(fill no)
			(layer "F.Fab")
		)
		(pad "1" smd custom
			(at 0 -0.4445 270)
			(size 0.1397 0.1397)
			(layers "F.Cu" "F.Mask" "F.Paste")
			(net "DRIVE_A_12_ACT")
			(options
				(clearance outline)
				(anchor circle)
			)
			(primitives
				(gr_poly
					(pts
						(arc
							(start -0.1778 -0.2794)
							(mid -0.249642 -0.249642)
							(end -0.2794 -0.1778)
						)
						(arc
							(start -0.2794 0.1778)
							(mid -0.249642 0.249642)
							(end -0.1778 0.2794)
						)
						(arc
							(start 0.1778 0.2794)
							(mid 0.249642 0.249642)
							(end 0.2794 0.1778)
						)
						(arc
							(start 0.2794 -0.1778)
							(mid 0.249642 -0.249642)
							(end 0.1778 -0.2794)
						)
					)
					(width 0)
					(fill yes)
				)
			)
		)
		(pad "2" smd custom
			(at 0 0.4445 270)
			(size 0.1397 0.1397)
			(layers "F.Cu" "F.Mask" "F.Paste")
			(net "GND")
			(options
				(clearance outline)
				(anchor circle)
			)
			(primitives
				(gr_poly
					(pts
						(arc
							(start -0.1778 -0.2794)
							(mid -0.249642 -0.249642)
							(end -0.2794 -0.1778)
						)
						(arc
							(start -0.2794 0.1778)
							(mid -0.249642 0.249642)
							(end -0.1778 0.2794)
						)
						(arc
							(start 0.1778 0.2794)
							(mid 0.249642 0.249642)
							(end 0.2794 0.1778)
						)
						(arc
							(start 0.2794 -0.1778)
							(mid 0.249642 -0.249642)
							(end 0.1778 -0.2794)
						)
					)
					(width 0)
					(fill yes)
				)
			)
		)
	)
)
